FILE_TYPE = CONNECTIVITY;
{Allegro Design Entry HDL 16.6-p007 (v16-6-112F) 10/10/2012}
"PAGE_NUMBER" = 154;
0"NC";
1"GND\g";
2"P3V3_STBY\g";
3"P3V3_STBY\g";
4"P3V3_STBY\g";
5"GND\g";
6"GND\g";
7"P3V3_STBY\g";
8"GND\g";
9"P3V3_STBY\g";
10"GND\g";
11"P3V3_STBY\g";
12"GND\g";
13"GND\g";
14"GND\g";
15"P3V3_STBY\g";
16"GND\g";
17"GND\g";
18"SPI_CS0_SECONDARY_N";
19"SPI_CS0_SECONDARY_R_N";
20"SPI_BMC_DI";
21"SPI_SWITCH_CS0_N";
22"SPI_SWITCH_MISO";
23"SPI_SWITCH_CLK";
24"SPI_SWITCH_MOSI";
25"SPI_PCH_IO3_R1";
26"SPI_PCH_IO3";
27"FM_BIOS_SPI_BMC_CTRL";
28"SPI_PCH_IO2";
29"SPI_PCH_IO2_R1";
30"TP_SPI_SWITCH1_11";
31"TP_SPI_SWITCH1_6";
32"TP_SPI_SWITCH1_3";
33"TP_SPI_SWITCH1_10";
34"TP_SPI_SWITCH1_13";
35"TP_SPI_SWITCH1_14";
36"SPI_BMC_CS0_N";
37"SPI_PCH_CS0_N";
38"SPI_PCH_MISO";
39"SPI_BMC_DO";
40"SPI_PCH_MOSI";
41"FM_BIOS_SPI_BMC_CTRL";
42"SPI_PCH_CLK";
43"SPI_BMC_CLK";
44"SPI_BIOS_SOCKET_IO2";
45"SPI_BIOS_SOCKET_IO3";
46"TP_SPI_SWITCH1_9";
47"SPI_PCH_MISO_R";
48"FM_BIOS_SPI_BMC_CTRL";
49"TP_SPI_SWITCH1_12";
50"SPI_CS0_PRIMARY_R_N";
51"FM_BACKUP_BIOS_SEL_N";
52"SPI_CS0_PRIMARY_N";
53"SPI_SWITCH_CS0_N";
54"FM_DUAL_BIOS_SEL_N";
%"TTL1G32_A"
"1","(-2275,1150)","0","mstr_ttl","I100";
;
CDS_SEC"1"
MATERIAL"IC"
LOCATION"U2T2"
VALUE"74LVC1G32"
POWER_GROUP"VCC=P3V3_STBY;GND=GND"
PART_NUMBER"E60229-001"
GROUP"NI_BIOS_ROM2"
ROOM"SB_BMC_SPI_MUX"
CDS_LOCATION"U2T2"
SEC"1"
BOM_COST"MIO_BIOS_MEM"
SEC_TYPE"SOT"
CDS_LIB"mstr_ttl"
PACK_TYPE"SOT";
"A"
$PN"1"51;
"Y"
$PN"4"18;
"B"
$PN"2"53;
%"RES"
"1","(-1450,1875)","0","mstr_discrete","I101";
;
CDS_SEC"1"
PACK_TYPE"0402"
MATERIAL"CHIP"
TOLERANCE"1%"
LOCATION"R2T13"
WATTAGE"1/16W"
PART_NUMBER"G21796-004"
VALUE"200.0"
GROUP"NI_BIOS_ROM2"
ROOM"SB_BMC_SPI_MUX"
CDS_LOCATION"R2T13"
SEC"1"
BOM_COST"MIO_BIOS_MEM"
CDS_LIB"mstr_discrete"
SEC_TYPE"0402";
"B"
$PN"2"50;
"A"
$PN"1"52;
%"RES"
"2","(-3100,2200)","0","mstr_discrete","I105";
;
CDS_SEC"1"
VALUE"4.75K"
LOCATION"R2T11"
MATERIAL"CHIP"
WATTAGE"1/16W"
TOLERANCE"1%"
PART_NUMBER"G21796-072"
PACK_TYPE"0402"
GROUP"NI_BIOS_ROM2"
ROOM"SB_BMC_SPI_MUX"
CDS_LOCATION"R2T11"
SEC"1"
BOM_COST"MIO_BIOS_MEM"
SEC_TYPE"0402"
CDS_LIB"mstr_discrete";
"A"
$PN"1"2;
"B"
$PN"2"54;
%"RES"
"2","(-3775,1750)","2","mstr_discrete","I106";
;
CDS_SEC"1"
VALUE"10.0K"
GROUP"NI_BIOS_ROM2"
LOCATION"R2T8"
WATTAGE"1/16W"
PART_NUMBER"G21796-016"
PACK_TYPE"0402"
MATERIAL"CHIP"
TOLERANCE"1%"
ROOM"SB_BMC_SPI_MUX"
CDS_LOCATION"R2T8"
SEC"1"
BOM_COST"MIO_BIOS_MEM"
SEC_TYPE"0402"
CDS_LIB"mstr_discrete";
"A"
$PN"1"3;
"B"
$PN"2"53;
%"GND"
"1","(-3100,1275)","0","mstr_symbols","I109";
;
HDL_POWER"GND"
BODY_TYPE"PLUMBING"
SIZE"1B"
CDS_LIB"mstr_symbols"
VOLTAGE"0.0V";
"A\NAC"1;
%"P3V3_STBY"
"1","(-3100,2450)","0","mstr_symbols","I110";
;
HDL_POWER"P3V3_STBY"
BODY_TYPE"PLUMBING"
CDS_LIB"mstr_symbols"
SIZE"1B"
VOLTAGE"3.3V";
"G\NAC"2;
%"P3V3_STBY"
"1","(-3775,2025)","0","mstr_symbols","I111";
;
HDL_POWER"P3V3_STBY"
BODY_TYPE"PLUMBING"
CDS_LIB"mstr_symbols"
SIZE"1B"
VOLTAGE"3.3V";
"G\NAC"3;
%"RES"
"1","(-6725,3600)","0","mstr_discrete","I119";
;
VALUE"0.0"
MATERIAL"CHIP"
LOCATION"R8F6"
TOLERANCE"5%"
PACK_TYPE"0402"
WATTAGE"1/16W"
PART_NUMBER"G21497-005"
CDS_LIB"mstr_discrete"
CDS_SEC"1"
$SEC"1"
CDS_LOCATION"R8F6"
ROOM"MIO_BIOS_MEM";
"B"
$PN"2"47;
"A"
$PN"1"38;
%"P3V3_STBY"
"1","(-5575,4600)","0","mstr_symbols","I12";
;
HDL_POWER"P3V3_STBY"
BODY_TYPE"PLUMBING"
SIZE"1B"
CDS_LIB"mstr_symbols"
VOLTAGE"3.3V";
"G\NAC"4;
%"FET_N"
"8","(-3100,1575)","0","mstr_discrete","I126";
;
CDS_SEC"1"
GROUP"NI_BIOS_ROM2"
MATERIAL"FET"
VALUE"2N7002"
LOCATION"Q8F1"
PART_NUMBER"C79254-001"
ROOM"SB_BMC_SPI_MUX"
CDS_LOCATION"Q8F1"
SEC"1"
SEC_TYPE"SOT23LF"
BOM_COST"MIO_BIOS_MEM"
CDS_LIB"mstr_discrete"
PACK_TYPE"SOT23LF";
"GATE"
$PN"1"51;
"DRN"
$PN"3"54;
"SRC"
$PN"2"1;
%"RES"
"2","(-3400,1750)","2","mstr_discrete","I127";
;
CDS_SEC"1"
PACK_TYPE"0402"
VALUE"4.75K"
LOCATION"R2T6"
TOLERANCE"1%"
WATTAGE"1/16W"
MATERIAL"CHIP"
PART_NUMBER"G21796-072"
ROOM"SB_BMC_SPI_MUX"
CDS_LOCATION"R2T6"
BOM_COST"MIO_BIOS_MEM"
CDS_LIB"mstr_discrete"
SEC"1"
SEC_TYPE"0402";
"A"
$PN"1"11;
"B"
$PN"2"51;
%"RES"
"2","(-6250,2750)","0","mstr_discrete","I128";
;
CDS_SEC"1"
PACK_TYPE"0402"
TOLERANCE"1%"
VALUE"10.0K"
LOCATION"R1U6"
WATTAGE"1/16W"
MATERIAL"CHIP"
PART_NUMBER"G21796-016"
ROOM"SB_BMC_BPI_MUX"
CDS_LOCATION"R1U6"
SEC"1"
SEC_TYPE"0402"
BOM_COST"MIO_BIOS_MEM"
CDS_LIB"mstr_discrete";
"A"
$PN"1"48;
"B"
$PN"2"5;
%"GND"
"1","(-6250,2450)","0","mstr_symbols","I129";
;
HDL_POWER"GND"
BODY_TYPE"PLUMBING"
CDS_LIB"mstr_symbols"
SIZE"1B"
VOLTAGE"0.0V";
"A\NAC"5;
%"GND"
"1","(-5400,4100)","0","mstr_symbols","I13";
;
HDL_POWER"GND"
BODY_TYPE"PLUMBING"
CDS_LIB"mstr_symbols"
SIZE"1B"
VOLTAGE"0.0V";
"A\NAC"6;
%"P3V3_STBY"
"1","(-375,2525)","0","mstr_symbols","I131";
;
HDL_POWER"P3V3_STBY"
BODY_TYPE"PLUMBING"
SIZE"1B"
CDS_LIB"mstr_symbols"
VOLTAGE"3.3V";
"G\NAC"7;
%"CAP_A"
"1","(-375,2225)","0","dev_discrete","I132";
;
VOLTAGE"16V"
TOLERANCE"10%"
MATERIAL"X7R"
PART_NUMBER"A36096-030"
PACK_TYPE"0402V"
VALUE"0.1UF"
LOCATION"C2T12"
SEC"1"
SEC_TYPE"0402V"
CDS_SEC"1"
CDS_LIB"dev_discrete"
BOM_COST"MIO_BIOS_MEM"
CDS_LOCATION"C2T12"
ROOM"SB_BMC_SPI_MUX";
"B"
$PN"2"8;
"A"
$PN"1"7;
%"GND"
"1","(-375,1925)","0","mstr_symbols","I133";
;
HDL_POWER"GND"
BODY_TYPE"PLUMBING"
SIZE"1B"
CDS_LIB"mstr_symbols"
VOLTAGE"0.0V";
"A\NAC"8;
%"P3V3_STBY"
"1","(-375,1700)","0","mstr_symbols","I134";
;
HDL_POWER"P3V3_STBY"
BODY_TYPE"PLUMBING"
SIZE"1B"
CDS_LIB"mstr_symbols"
VOLTAGE"3.3V";
"G\NAC"9;
%"CAP_A"
"1","(-375,1475)","0","dev_discrete","I135";
;
TOLERANCE"10%"
VOLTAGE"16V"
MATERIAL"X7R"
VALUE"0.1UF"
LOCATION"C2T8"
PART_NUMBER"A36096-030"
PACK_TYPE"0402V"
ROOM"SB_BMC_SPI_MUX"
CDS_LOCATION"C2T8"
BOM_COST"MIO_BIOS_MEM"
CDS_LIB"dev_discrete"
CDS_SEC"1"
SEC_TYPE"0402V"
SEC"1";
"B"
$PN"2"10;
"A"
$PN"1"9;
%"GND"
"1","(-375,1250)","0","mstr_symbols","I136";
;
HDL_POWER"GND"
BODY_TYPE"PLUMBING"
VOLTAGE"0.0V"
CDS_LIB"mstr_symbols"
SIZE"1B";
"A\NAC"10;
%"P3V3_STBY"
"1","(-3400,2025)","0","mstr_symbols","I137";
;
HDL_POWER"P3V3_STBY"
BODY_TYPE"PLUMBING"
CDS_LIB"mstr_symbols"
SIZE"1B"
VOLTAGE"3.3V";
"G\NAC"11;
%"CAP_A"
"1","(-5400,4350)","0","dev_discrete","I14";
;
PACK_TYPE"0402V"
MATERIAL"X7R"
VOLTAGE"16V"
TOLERANCE"10%"
VALUE"0.1UF"
PART_NUMBER"A36096-030"
LOCATION"C8E18"
SEC"1"
SEC_TYPE"0402V"
CDS_SEC"1"
CDS_LIB"dev_discrete"
BOM_COST"MIO_BIOS_MEM"
CDS_LOCATION"C8E18"
ROOM"SB_BMC_SPI_MUX";
"B"
$PN"2"6;
"A"
$PN"1"4;
%"RES"
"1","(-1450,1150)","0","mstr_discrete","I62";
;
CDS_SEC"1"
PACK_TYPE"0402"
LOCATION"R2T9"
VALUE"75"
TOLERANCE"1.0%"
WATTAGE"1/16W"
PART_NUMBER"G21796-267"
MATERIAL"CHIP"
GROUP"NI_BIOS_ROM2"
ROOM"SB_BMC_SPI_MUX"
CDS_LOCATION"R2T9"
SEC"1"
SEC_TYPE"0402"
CDS_LIB"mstr_discrete"
BOM_COST"MIO_BIOS_MEM";
"B"
$PN"2"19;
"A"
$PN"1"18;
%"PI3B3257A"
"1","(-5900,3700)","2","mstr_digital","I74";
;
CDS_SEC"1"
MATERIAL"IC"
LOCATION"U8F1"
PART_NUMBER"E16801-001"
ROOM"SB_BMC_SPI_MUX"
CDS_LOCATION"U8F1"
SEC"1"
CDS_LIB"mstr_digital"
SEC_TYPE"TSSOPLF"
BOM_COST"MIO_BIOS_MEM"
PACK_TYPE"TSSOPLF";
"YC"
$PN"9"21;
"YD"
$PN"12"22;
"IC1"
$PN"10"36;
"IC0"
$PN"11"37;
"IB1"
$PN"6"39;
"YA"
$PN"4"23;
"GND"
$PN"8"12;
"EN \B"
$PN"15"13;
"IA0"
$PN"2"42;
"S"
$PN"1"41;
"IB0"
$PN"5"40;
"IA1"
$PN"3"43;
"ID0"
$PN"14"47;
"ID1"
$PN"13"20;
"YB"
$PN"7"24;
"VCC"
$PN"16"4;
%"PI3B3257A"
"1","(-2000,3875)","2","mstr_digital","I75";
;
CDS_SEC"1"
MATERIAL"IC"
PART_NUMBER"E16801-001"
LOCATION"U2T1"
ROOM"SB_BMC_SPI_MUX"
CDS_LOCATION"U2T1"
SEC"1"
CDS_LIB"mstr_digital"
SEC_TYPE"TSSOPLF"
BOM_COST"MIO_BIOS_MEM"
PACK_TYPE"TSSOPLF";
"YC"
$PN"9"46;
"YD"
$PN"12"49;
"IC1"
$PN"10"33;
"IC0"
$PN"11"30;
"IB1"
$PN"6"31;
"YA"
$PN"4"44;
"GND"
$PN"8"17;
"EN \B"
$PN"15"16;
"IA0"
$PN"2"29;
"S"
$PN"1"27;
"IB0"
$PN"5"25;
"IA1"
$PN"3"32;
"ID0"
$PN"14"35;
"ID1"
$PN"13"34;
"YB"
$PN"7"45;
"VCC"
$PN"16"15;
%"GND"
"1","(-5625,3325)","0","mstr_symbols","I85";
;
HDL_POWER"GND"
BODY_TYPE"PLUMBING"
SIZE"1B"
CDS_LIB"mstr_symbols"
VOLTAGE"0.0V";
"A\NAC"12;
%"GND"
"1","(-6175,3325)","0","mstr_symbols","I86";
;
HDL_POWER"GND"
BODY_TYPE"PLUMBING"
SIZE"1B"
CDS_LIB"mstr_symbols"
VOLTAGE"0.0V";
"A\NAC"13;
%"RES"
"1","(-3200,3975)","0","mstr_discrete","I92";
;
CDS_SEC"1"
LOCATION"R2T2"
VALUE"0.0"
TOLERANCE"5%"
WATTAGE"1/16W"
MATERIAL"CHIP"
PACK_TYPE"0402"
PART_NUMBER"G21497-005"
SEC_TYPE"0402"
CDS_LIB"mstr_discrete"
BOM_COST"MIO_BIOS_MEM"
SEC"1"
CDS_LOCATION"R2T2"
ROOM"SB_BMC_SPI_MUX";
"B"
$PN"2"25;
"A"
$PN"1"26;
%"RES"
"1","(-3200,4075)","0","mstr_discrete","I93";
;
CDS_SEC"1"
LOCATION"R2R12"
PART_NUMBER"G21497-005"
TOLERANCE"5%"
MATERIAL"CHIP"
PACK_TYPE"0402"
WATTAGE"1/16W"
VALUE"0.0"
SEC_TYPE"0402"
CDS_LIB"mstr_discrete"
BOM_COST"MIO_BIOS_MEM"
SEC"1"
CDS_LOCATION"R2R12"
ROOM"SB_BMC_SPI_MUX";
"B"
$PN"2"29;
"A"
$PN"1"28;
%"CAP_A"
"1","(-1500,4525)","0","dev_discrete","I94";
;
MATERIAL"X7R"
VOLTAGE"16V"
TOLERANCE"10%"
VALUE"0.1UF"
LOCATION"C2T1"
PART_NUMBER"A36096-030"
PACK_TYPE"0402V"
SEC"1"
SEC_TYPE"0402V"
CDS_SEC"1"
CDS_LIB"dev_discrete"
BOM_COST"MIO_BIOS_MEM"
CDS_LOCATION"C2T1"
ROOM"SB_BMC_SPI_MUX";
"B"
$PN"2"14;
"A"
$PN"1"15;
%"GND"
"1","(-1500,4275)","0","mstr_symbols","I95";
;
HDL_POWER"GND"
BODY_TYPE"PLUMBING"
SIZE"1B"
CDS_LIB"mstr_symbols"
VOLTAGE"0.0V";
"A\NAC"14;
%"P3V3_STBY"
"1","(-1675,4775)","0","mstr_symbols","I96";
;
HDL_POWER"P3V3_STBY"
BODY_TYPE"PLUMBING"
SIZE"1B"
CDS_LIB"mstr_symbols"
VOLTAGE"3.3V";
"G\NAC"15;
%"GND"
"1","(-2275,3500)","0","mstr_symbols","I97";
;
HDL_POWER"GND"
BODY_TYPE"PLUMBING"
SIZE"1B"
CDS_LIB"mstr_symbols"
VOLTAGE"0.0V";
"A\NAC"16;
%"GND"
"1","(-1725,3500)","0","mstr_symbols","I98";
;
HDL_POWER"GND"
BODY_TYPE"PLUMBING"
SIZE"1B"
CDS_LIB"mstr_symbols"
VOLTAGE"0.0V";
"A\NAC"17;
%"TTL1G32_A"
"1","(-2275,1875)","0","mstr_ttl","I99";
;
CDS_SEC"1"
PART_NUMBER"E60229-001"
MATERIAL"IC"
VALUE"74LVC1G32"
LOCATION"U2T3"
POWER_GROUP"VCC=P3V3_STBY;GND=GND"
GROUP"NI_BIOS_ROM2"
ROOM"SB_BMC_SPI_MUX"
CDS_LOCATION"U2T3"
SEC"1"
CDS_LIB"mstr_ttl"
SEC_TYPE"SOT"
BOM_COST"MIO_BIOS_MEM"
PACK_TYPE"SOT";
"A"
$PN"1"54;
"Y"
$PN"4"52;
"B"
$PN"2"53;
END.
